#ISCELL
  mstr_misc dns *
  *
#ISCELL
  mstr_symbols design_note *
  *
#ISCELL
  mstr_symbols intel_corp_bpage *
  *
#ISCELL
  mstr_standard offpage *
  page210_i1
#CELL
  mstr_discrete capp *
  page210_i12
#ISCELL
  mstr_symbols gnd *
  page210_i13
#CELL
  mstr_discrete capp *
  page210_i14
#ISCELL
  mstr_symbols gnd *
  page210_i15
#ISCELL
  mstr_standard offpage *
  page210_i17
#ISCELL
  mstr_standard offpage *
  page210_i18
#ISCELL
  mstr_standard offpage *
  page210_i2
#ISCELL
  mstr_symbols vcc_core *
  page210_i21
#CELL
  mstr_discrete cap *
  page210_i22
#CELL
  mstr_discrete cap *
  page210_i24
#CELL
  mstr_discrete cap *
  page210_i26
#CELL
  dev_discrete cap_a *
  page210_i27
#CELL
  mstr_discrete cap *
  page210_i28
#CELL
  mstr_discrete res *
  page210_i29
#ISCELL
  mstr_symbols gnd *
  page210_i30
#CELL
  mstr_discrete res *
  page210_i31
#CELL
  mstr_discrete res *
  page210_i32
#CELL
  mstr_discrete res *
  page210_i33
#CELL
  mstr_discrete res *
  page210_i34
#CELL
  mstr_discrete cap *
  page210_i35
#CELL
  mstr_discrete cap *
  page210_i36
#CELL
  mstr_discrete cap *
  page210_i38
#ISCELL
  mstr_symbols gnd *
  page210_i39
#ISCELL
  mstr_standard offpage *
  page210_i40
#ISCELL
  mstr_standard offpage *
  page210_i41
#ISCELL
  mstr_symbols p5v_stby *
  page210_i42
#CELL
  dev_discrete cap_a *
  page210_i44
#CELL
  mstr_discrete res *
  page210_i45
#ISCELL
  mstr_symbols pvsa_cpu1 *
  page210_i46
#ISCELL
  mstr_symbols pvsa_cpu1 *
  page210_i47
#ISCELL
  mstr_standard offpage *
  page210_i50
#CELL
  mstr_discrete ir354xx *
  page210_i51
#CELL
  mstr_discrete res *
  page210_i52
#ISCELL
  mstr_symbols gnd *
  page210_i53
#ISCELL
  mstr_symbols gnd *
  page210_i54
#CELL
  dev_discrete cap_a *
  page210_i55
#ISCELL
  mstr_symbols gnd *
  page210_i58
#ISCELL
  mstr_standard offpage *
  page210_i6
#CELL
  mstr_discrete cap *
  page210_i60
#ISCELL
  mstr_symbols gnd *
  page210_i61
#CELL
  mstr_discrete cap *
  page210_i66
#CELL
  mstr_discrete res *
  page210_i68
#ISCELL
  mstr_symbols pvsa_cpu1 *
  page210_i7
#CELL
  mstr_discrete res *
  page210_i71
#CELL
  w_hdl ind-300nh-20-gp *
  page210_i72
#CELL
  w_hdl sc1u10v2kx-4-gp *
  page210_i73
#CELL
  w_hdl 1r3f-gp *
  page210_i74
#CELL
  dev_discrete cap_a *
  page210_i8
#ISCELL
  mstr_symbols gnd *
  page210_i9
